# S9S_MB_2U (Grand Teton) — schematic netlist excerpt (pin names and nets, part order shuffled) for the footprints in the layout excerpt that follows; sources: Cadence DE-HDL packaged netlist, KiCad conversion of 03242023_DA0F0TMBIJ0_F0T_Motherboard_J_brd_V01_OCP.brd

C231  Q_CAP  10UF 6.3V 20% X6S  pkg C0402  page 77 : A = PVCCIN_CPU1 ; B = GND
R1455  Q_RES  49.9 1% CHIP  pkg 0402LF  page 205 : A = FM_ADR_MODE0_R ; B = FM_ADR_MODE0

(kicad_pcb
	(version 20260206)
	(generator "pcbnew")
	(generator_version "10.0")
	(general
		(thickness 1.6)
		(legacy_teardrops no)
	)
	(paper "A4")
	(title_block
		(title "03242023_DA0F0TMBIJ0_F0T_Motherboard_J_brd_V01_OCP.brd")
		(comment 1 "Grand Teton / footprints 2567-2568 of 6105")
	)
	(layers
		(0 "F.Cu" signal "TOP")
		(4 "In1.Cu" signal "GND")
		(6 "In2.Cu" signal "IN1")
		(8 "In3.Cu" signal "GND1")
		(10 "In4.Cu" signal "IN2")
		(12 "In5.Cu" signal "GND2")
		(14 "In6.Cu" signal "IN3")
		(16 "In7.Cu" signal "GND3")
		(18 "In8.Cu" signal "VCC")
		(20 "In9.Cu" signal "VCC1")
		(22 "In10.Cu" signal "GND4")
		(24 "In11.Cu" signal "IN4")
		(26 "In12.Cu" signal "GND5")
		(28 "In13.Cu" signal "IN5")
		(30 "In14.Cu" signal "GND6")
		(32 "In15.Cu" signal "IN6")
		(34 "In16.Cu" signal "GND7")
		(2 "B.Cu" signal "BOTTOM")
		(9 "F.Adhes" user "F.Adhesive")
		(11 "B.Adhes" user "B.Adhesive")
		(13 "F.Paste" user "Package Geometry/Pastemask Top")
		(15 "B.Paste" user "Package Geometry/Pastemask Bottom")
		(5 "F.SilkS" user "Ref Des/Silkscreen Top")
		(7 "B.SilkS" user "Ref Des/Silkscreen Bottom")
		(1 "F.Mask" user "Board Geometry/Soldermask Top")
		(3 "B.Mask" user "Board Geometry/Soldermask Bottom")
		(17 "Dwgs.User" user "User.Drawings")
		(19 "Cmts.User" user "User.Comments")
		(21 "Eco1.User" user "User.Eco1")
		(23 "Eco2.User" user "User.Eco2")
		(25 "Edge.Cuts" user "Board Geometry/Outline")
		(27 "Margin" user)
		(31 "F.CrtYd" user "Package Geometry/Place Bound Top")
		(29 "B.CrtYd" user "Package Geometry/Place Bound Bottom")
		(35 "F.Fab" user "Ref Des/Assembly Top")
		(33 "B.Fab" user "Ref Des/Assembly Bottom")
	)
	(footprint ""
		(layer "F.Cu")
		(at 322.263516 -22.497288)
		(property "Reference" "R1455"
			(at 0 0 0)
			(layer "F.SilkS")
			(hide yes)
			(effects
				(font
					(size 1.27 1.27)
				)
			)
		)
		(property "Value" ""
			(at 0 0 0)
			(layer "F.Fab")
			(effects
				(font
					(size 1.27 1.27)
				)
			)
		)
		(duplicate_pad_numbers_are_jumpers no)
		(fp_line
			(start -0.7874 -0.4064)
			(end 0.7874 -0.4064)
			(stroke
				(width 0.1524)
				(type default)
			)
			(layer "F.SilkS")
		)
		(fp_line
			(start -0.7874 0.4064)
			(end -0.7874 -0.4064)
			(stroke
				(width 0.1524)
				(type default)
			)
			(layer "F.SilkS")
		)
		(fp_line
			(start 0.7874 -0.4064)
			(end 0.7874 0.4064)
			(stroke
				(width 0.1524)
				(type default)
			)
			(layer "F.SilkS")
		)
		(fp_line
			(start 0.7874 0.4064)
			(end -0.7874 0.4064)
			(stroke
				(width 0.1524)
				(type default)
			)
			(layer "F.SilkS")
		)
		(fp_line
			(start -0.67945 -0.305054)
			(end -0.12065 -0.305054)
			(stroke
				(width 0.1)
				(type default)
			)
			(layer "F.Fab")
		)
		(fp_line
			(start -0.67945 0.3048)
			(end -0.67945 -0.305054)
			(stroke
				(width 0.1)
				(type default)
			)
			(layer "F.Fab")
		)
		(fp_line
			(start -0.12065 -0.305054)
			(end -0.12065 -0.2794)
			(stroke
				(width 0.1)
				(type default)
			)
			(layer "F.Fab")
		)
		(fp_line
			(start -0.12065 -0.2794)
			(end 0.12065 -0.2794)
			(stroke
				(width 0.1)
				(type default)
			)
			(layer "F.Fab")
		)
		(fp_line
			(start -0.12065 0.2794)
			(end -0.12065 0.3048)
			(stroke
				(width 0.1)
				(type default)
			)
			(layer "F.Fab")
		)
		(fp_line
			(start -0.12065 0.3048)
			(end -0.67945 0.3048)
			(stroke
				(width 0.1)
				(type default)
			)
			(layer "F.Fab")
		)
		(fp_line
			(start 0.120396 0.2794)
			(end -0.12065 0.2794)
			(stroke
				(width 0.1)
				(type default)
			)
			(layer "F.Fab")
		)
		(fp_line
			(start 0.120396 0.3048)
			(end 0.120396 0.2794)
			(stroke
				(width 0.1)
				(type default)
			)
			(layer "F.Fab")
		)
		(fp_line
			(start 0.12065 -0.3048)
			(end 0.67945 -0.3048)
			(stroke
				(width 0.1)
				(type default)
			)
			(layer "F.Fab")
		)
		(fp_line
			(start 0.12065 -0.2794)
			(end 0.12065 -0.3048)
			(stroke
				(width 0.1)
				(type default)
			)
			(layer "F.Fab")
		)
		(fp_line
			(start 0.67945 -0.3048)
			(end 0.67945 0.3048)
			(stroke
				(width 0.1)
				(type default)
			)
			(layer "F.Fab")
		)
		(fp_line
			(start 0.67945 0.3048)
			(end 0.120396 0.3048)
			(stroke
				(width 0.1)
				(type default)
			)
			(layer "F.Fab")
		)
		(pad "1" smd circle
			(at -0.40005 0)
			(size 0 0)
			(layers "F.Cu" "F.Mask" "F.Paste")
			(net "FM_ADR_MODE0_R")
		)
		(pad "2" smd circle
			(at 0.40005 0)
			(size 0 0)
			(layers "F.Cu" "F.Mask" "F.Paste")
			(net "FM_ADR_MODE0")
		)
	)
	(footprint ""
		(layer "F.Cu")
		(at 106.3117 -256.6543 -90)
		(property "Reference" "C231"
			(at 0 0 270)
			(layer "F.SilkS")
			(hide yes)
			(effects
				(font
					(size 1.27 1.27)
				)
			)
		)
		(property "Value" ""
			(at 0 0 270)
			(layer "F.Fab")
			(effects
				(font
					(size 1.27 1.27)
				)
			)
		)
		(duplicate_pad_numbers_are_jumpers no)
		(fp_line
			(start -0.7874 0.4064)
			(end -0.7874 -0.4064)
			(stroke
				(width 0.1524)
				(type default)
			)
			(layer "F.SilkS")
		)
		(fp_line
			(start 0.7874 0.4064)
			(end -0.7874 0.4064)
			(stroke
				(width 0.1524)
				(type default)
			)
			(layer "F.SilkS")
		)
		(fp_line
			(start -0.7874 -0.4064)
			(end 0.7874 -0.4064)
			(stroke
				(width 0.1524)
				(type default)
			)
			(layer "F.SilkS")
		)
		(fp_line
			(start 0.7874 -0.4064)
			(end 0.7874 0.4064)
			(stroke
				(width 0.1524)
				(type default)
			)
			(layer "F.SilkS")
		)
		(fp_line
			(start -0.67945 0.3048)
			(end -0.67945 -0.305054)
			(stroke
				(width 0.1)
				(type default)
			)
			(layer "F.Fab")
		)
		(fp_line
			(start -0.12065 0.3048)
			(end -0.67945 0.3048)
			(stroke
				(width 0.1)
				(type default)
			)
			(layer "F.Fab")
		)
		(fp_line
			(start 0.120396 0.3048)
			(end 0.120396 0.2794)
			(stroke
				(width 0.1)
				(type default)
			)
			(layer "F.Fab")
		)
		(fp_line
			(start 0.67945 0.3048)
			(end 0.120396 0.3048)
			(stroke
				(width 0.1)
				(type default)
			)
			(layer "F.Fab")
		)
		(fp_line
			(start -0.12065 0.2794)
			(end -0.12065 0.3048)
			(stroke
				(width 0.1)
				(type default)
			)
			(layer "F.Fab")
		)
		(fp_line
			(start 0.120396 0.2794)
			(end -0.12065 0.2794)
			(stroke
				(width 0.1)
				(type default)
			)
			(layer "F.Fab")
		)
		(fp_line
			(start -0.12065 -0.2794)
			(end 0.12065 -0.2794)
			(stroke
				(width 0.1)
				(type default)
			)
			(layer "F.Fab")
		)
		(fp_line
			(start 0.12065 -0.2794)
			(end 0.12065 -0.3048)
			(stroke
				(width 0.1)
				(type default)
			)
			(layer "F.Fab")
		)
		(fp_line
			(start 0.12065 -0.3048)
			(end 0.67945 -0.3048)
			(stroke
				(width 0.1)
				(type default)
			)
			(layer "F.Fab")
		)
		(fp_line
			(start 0.67945 -0.3048)
			(end 0.67945 0.3048)
			(stroke
				(width 0.1)
				(type default)
			)
			(layer "F.Fab")
		)
		(fp_line
			(start -0.67945 -0.305054)
			(end -0.12065 -0.305054)
			(stroke
				(width 0.1)
				(type default)
			)
			(layer "F.Fab")
		)
		(fp_line
			(start -0.12065 -0.305054)
			(end -0.12065 -0.2794)
			(stroke
				(width 0.1)
				(type default)
			)
			(layer "F.Fab")
		)
		(pad "1" smd circle
			(at -0.40005 0 270)
			(size 0 0)
			(layers "F.Cu" "F.Mask" "F.Paste")
			(net "PVCCIN_CPU1")
		)
		(pad "2" smd circle
			(at 0.40005 0 270)
			(size 0 0)
			(layers "F.Cu" "F.Mask" "F.Paste")
			(net "GND")
		)
	)
)
